FILE_TYPE = CONNECTIVITY;
{Allegro Design Entry HDL 16.6-p007 (v16-6-112F) 10/10/2012}
"PAGE_NUMBER" = 216;
0"NC";
1"PVDDQ_ABC\g";
2"GND\g";
3"GND\g";
4"GND\g";
5"GND\g";
6"GND\g";
7"GND\g";
8"GND\g";
9"GND\g";
10"GND\g";
11"GND\g";
12"PVDDQ_ABC\g";
13"GND\g";
14"GND\g";
15"GND\g";
16"VR_FET_SW_P12V_STBY_PVDDQ_ABC\g";
17"GND\g";
18"VR_FET_SW_P12V_STBY_PVDDQ_ABC\g";
19"P5V_STBY\g";
20"P5V_STBY\g";
21"VR_PVDDQ_ABC_PH2_PHASE";
22"TP_PVDDQ_ABC_PH2_GL_1";
23"VR_PVDDQ_ABC_PH2_VCIN";
24"UN$216$3D01R5F-GP$I114$2";
25"VR_PVDDQ_ABC_PH1_SW";
26"VR_PVDDQ_ABC_PH2_SW";
27"UN$216$3D01R5F-GP$I123$2";
28"VR_PVDDQ_ABC_PH2_BOOT_R";
29"VR_PVDDQ_ABC_PH2_BOOT";
30"VR_PVDDQ_ABC_PWM2";
31"A_TSENSE_PVDDQ_ABC";
32"VR_PVDDQ_ABC_PH1_OCSET"VOLTAGE"3.6";
33"VR_PVDDQ_ABC_PH1_PHASE";
34"VR_PVDDQ_ABC_PH1_BOOT_R";
35"VR_PVDDQ_ABC_AIREF1";
36"VR_PVDDQ_ABC_PH1_BOOT";
37"VR_PVDDQ_ABC_PH2_OCSET"VOLTAGE"3.6";
38"VR_PVDDQ_ABC_PWM1";
39"VR_PVDDQ_ABC_AIREF2";
40"A_TSENSE_PVDDQ_ABC";
41"ISENSE_PVDDQ_ABC_PH2_IMON";
42"NC_PVDDQ_ABC_PH1_P31";
43"TP_PVDDQ_ABC_PH2_GL_0";
44"NC_PVDDQ_ABC_PH2_P31";
45"TP_PVDDQ_ABC_PH1_GL_1";
46"TP_PVDDQ_ABC_PH1_GL_0";
47"VR_PVDDQ_ABC_PH1_VCIN";
48"ISENSE_PVDDQ_ABC_PH1_IMON";
%"PVDDQ_ABC"
"1","(4000,2050)","0","mstr_symbols","I1";
;
CDS_LIB"mstr_symbols"
HDL_POWER"PVDDQ_ABC"
BODY_TYPE"PLUMBING"
VOLTAGE"1.2V";
"G\NAC"1;
%"IR354XX"
"1","(1425,2250)","0","mstr_discrete","I102";
;
CDS_SEC"1"
CDS_LIB"mstr_discrete"
PACK_TYPE"SM"
SEC_TYPE"SM"
SEC"1"
CDS_LOCATION"EU7G2"
PART_NUMBER"H73688-001"
VALUE"IR35411"
LOCATION"EU7G2"
MATERIAL"IC"
NO_XNET_CONNECTION"1";
"TOUT_FLT"
$PN"36"31;
"NC"
$PN"31"42;
"OCSET"
$PN"37"32;
"IOUT"
$PN"38"48;
"SW"
$PN"10"25;
"BOOST"
$PN"33"34;
"REFIN"
$PN"39"35;
"PWM"
$PN"34"38;
"PHASE"
$PN"32"33;
"VIN<0>"
$PN"25"18;
"VCC"
$PN"3"47;
"VIN<1>"
$PN"30"18;
"EN"
$PN"35"19;
"VDRV"
$PN"4"19;
"VOS"
$PN"1"1;
"LGND"
$PN"2"10;
"PGND<1>"
$PN"7"10;
"PGND<2>"
$PN"40"10;
"PGND<0>"
$PN"5"10;
"GL<0>"
$PN"6"46;
"GL<1>"
$PN"41"45;
%"IR354XX"
"1","(1425,-125)","0","mstr_discrete","I103";
;
CDS_SEC"1"
PACK_TYPE"SM"
SEC_TYPE"SM"
SEC"1"
CDS_LOCATION"EU7G3"
CDS_LIB"mstr_discrete"
NO_XNET_CONNECTION"1"
LOCATION"EU7G3"
PART_NUMBER"H73688-001"
VALUE"IR35411"
MATERIAL"IC";
"TOUT_FLT"
$PN"36"40;
"NC"
$PN"31"44;
"OCSET"
$PN"37"37;
"IOUT"
$PN"38"41;
"SW"
$PN"10"26;
"BOOST"
$PN"33"28;
"REFIN"
$PN"39"39;
"PWM"
$PN"34"30;
"PHASE"
$PN"32"21;
"VIN<0>"
$PN"25"16;
"VCC"
$PN"3"23;
"VIN<1>"
$PN"30"16;
"EN"
$PN"35"20;
"VDRV"
$PN"4"20;
"VOS"
$PN"1"12;
"LGND"
$PN"2"15;
"PGND<1>"
$PN"7"15;
"PGND<2>"
$PN"40"15;
"PGND<0>"
$PN"5"15;
"GL<0>"
$PN"6"43;
"GL<1>"
$PN"41"22;
%"RES"
"2","(4225,2400)","0","mstr_discrete","I104";
;
CDS_SEC"1"
CDS_LOCATION"R7G25"
SEC_TYPE"0402"
SEC"1"
CDS_LIB"mstr_discrete"
MATERIAL"EMPTY"
LOCATION"R7G25"
PART_NUMBER"G21796-187"
VALUE"68.1K"
PACK_TYPE"0402"
WATTAGE"1/16W"
TOLERANCE"1%";
"A"
$PN"1"32;
"B"
$PN"2"2;
%"GND"
"1","(4225,2100)","0","mstr_symbols","I105";
;
HDL_POWER"GND"
SIZE"1B"
CDS_LIB"mstr_symbols"
VOLTAGE"0"
BODY_TYPE"PLUMBING"
BOM_COST"PROC_VRD_VCCIN_CPU0"
ROOM"PVCCIN_CPU0_PWR_VR";
"A\NAC"2;
%"RES"
"2","(4325,0)","0","mstr_discrete","I106";
;
CDS_SEC"1"
CDS_LOCATION"R7G30"
SEC_TYPE"0402"
SEC"1"
CDS_LIB"mstr_discrete"
LOCATION"R7G30"
VALUE"68.1K"
TOLERANCE"1%"
WATTAGE"1/16W"
PART_NUMBER"G21796-187"
PACK_TYPE"0402"
MATERIAL"EMPTY";
"A"
$PN"1"37;
"B"
$PN"2"3;
%"GND"
"1","(4325,-225)","0","mstr_symbols","I107";
;
SIZE"1B"
HDL_POWER"GND"
VOLTAGE"0"
CDS_LIB"mstr_symbols"
BODY_TYPE"PLUMBING"
BOM_COST"PROC_VRD_VCCIN_CPU0"
ROOM"PVCCIN_CPU0_PWR_VR";
"A\NAC"3;
%"CAP_A"
"1","(675,1750)","0","dev_discrete","I108";
;
CDS_SEC"1"
$SEC"1"
CDS_LOCATION"CT51"
ROOM"PVCCIN_CPU0_PWR_VR"
CDS_LIB"dev_discrete"
MATERIAL"X7R"
PART_NUMBER"A36096-030"
PACK_TYPE"0402V"
LOCATION"CT51"
VALUE"0.1UF"
VOLTAGE"16V"
TOLERANCE"10%"
STATUS"NOPOP";
"B"
$PN"2"4;
"A"
$PN"1"35;
%"GND"
"1","(675,1500)","0","mstr_symbols","I109";
;
BODY_TYPE"PLUMBING"
ROOM"PVCCIN_CPU0_PWR_VR"
BOM_COST"PROC_VRD_VCCIN_CPU0"
SIZE"1B"
VOLTAGE"0"
HDL_POWER"GND"
CDS_LIB"mstr_symbols";
"A\NAC"4;
%"CAP_A"
"1","(775,-625)","0","dev_discrete","I111";
;
CDS_SEC"1"
$SEC"1"
CDS_LOCATION"CT52"
CDS_LIB"dev_discrete"
ROOM"PVCCIN_CPU0_PWR_VR"
LOCATION"CT52"
VALUE"0.1UF"
VOLTAGE"16V"
TOLERANCE"10%"
PACK_TYPE"0402V"
STATUS"NOPOP"
MATERIAL"X7R"
PART_NUMBER"A36096-030";
"B"
$PN"2"5;
"A"
$PN"1"39;
%"GND"
"1","(775,-875)","0","mstr_symbols","I112";
;
CDS_LIB"mstr_symbols"
HDL_POWER"GND"
VOLTAGE"0"
SIZE"1B"
BOM_COST"PROC_VRD_VCCIN_CPU0"
ROOM"PVCCIN_CPU0_PWR_VR"
BODY_TYPE"PLUMBING";
"A\NAC"5;
%"3D01R5F-GP"
"1","(2750,1475)","4","w_hdl","I114";
;
CDS_SEC"1"
$SEC"1"
CDS_LOCATION"RT34"
PACK_TYPE"SMD-RG5"
PART_NUMBER"64.3R015.16L"
CDS_LIB"w_hdl"
CDS_LMAN_SYM_OUTLINE"-50,75,50,-75"
VALUE"3D01R5F-GP"
STATUS"NOPOP"
LOCATION"RT34";
"2"
$PN"2"24;
"1"
$PN"1"6;
%"GND"
"1","(2750,1225)","0","mstr_symbols","I115";
;
ROOM"PVCCIN_CPU0_PWR_VR"
BOM_COST"PROC_VRD_VCCIN_CPU0"
BODY_TYPE"PLUMBING"
VOLTAGE"0"
SIZE"1B"
HDL_POWER"GND"
CDS_LIB"mstr_symbols";
"A\NAC"6;
%"GND"
"1","(2650,2125)","0","mstr_symbols","I117";
;
CDS_LIB"mstr_symbols"
HDL_POWER"GND"
SIZE"1B"
BODY_TYPE"PLUMBING"
VOLTAGE"0"
ROOM"VDDQ_KLM_PWR_VR";
"A\NAC"7;
%"CAP"
"1","(2650,2325)","0","mstr_discrete","I118";
;
CDS_SEC"1"
$SEC"1"
CDS_LOCATION"CT49"
CDS_LIB"mstr_discrete"
ROOM"VDDQ_KLM_PWR_VR"
STATUS"NOPOP"
PART_NUMBER"A36096-046"
PACK_TYPE"0402LF"
MATERIAL"X7R"
VALUE"1000PF"
VOLTAGE"50V"
TOLERANCE"10%"
LOCATION"CT49";
"A"
$PN"1"31;
"B"
$PN"2"7;
%"SC2K2P50V3KX-GP"
"1","(2700,-600)","0","w_hdl","I119";
;
CDS_SEC"1"
$SEC"1"
CDS_LOCATION"CT53"
PACK_TYPE"SMD-BCG6"
PART_NUMBER"78.22224.2BL"
CDS_LMAN_SYM_OUTLINE"-50,25,50,-25"
CDS_LIB"w_hdl"
STATUS"NOPOP"
LOCATION"CT53"
VALUE"SC2K2P50V3KX-GP";
"2"
$PN"2"27;
"1"
$PN"1"26;
%"GND"
"1","(2700,-1150)","0","mstr_symbols","I120";
;
HDL_POWER"GND"
SIZE"1B"
VOLTAGE"0"
BODY_TYPE"PLUMBING"
BOM_COST"PROC_VRD_VCCIN_CPU0"
ROOM"PVCCIN_CPU0_PWR_VR"
CDS_LIB"mstr_symbols";
"A\NAC"8;
%"CAP"
"1","(2550,-125)","0","mstr_discrete","I121";
;
CDS_SEC"1"
$SEC"1"
CDS_LOCATION"CT54"
CDS_LIB"mstr_discrete"
ROOM"VDDQ_KLM_PWR_VR"
PART_NUMBER"A36096-046"
MATERIAL"X7R"
STATUS"NOPOP"
TOLERANCE"10%"
LOCATION"CT54"
VOLTAGE"50V"
PACK_TYPE"0402LF"
VALUE"1000PF";
"A"
$PN"1"40;
"B"
$PN"2"9;
%"GND"
"1","(2550,-325)","0","mstr_symbols","I122";
;
CDS_LIB"mstr_symbols"
ROOM"VDDQ_KLM_PWR_VR"
VOLTAGE"0"
BODY_TYPE"PLUMBING"
SIZE"1B"
HDL_POWER"GND";
"A\NAC"9;
%"3D01R5F-GP"
"1","(2700,-900)","4","w_hdl","I123";
;
CDS_SEC"1"
$SEC"1"
CDS_LOCATION"RT35"
PACK_TYPE"SMD-RG5"
PART_NUMBER"64.3R015.16L"
CDS_LIB"w_hdl"
CDS_LMAN_SYM_OUTLINE"-50,75,50,-75"
LOCATION"RT35"
VALUE"3D01R5F-GP"
STATUS"NOPOP";
"2"
$PN"2"27;
"1"
$PN"1"8;
%"SC2K2P50V3KX-GP"
"1","(2750,1800)","0","w_hdl","I124";
;
CDS_SEC"1"
$SEC"1"
CDS_LOCATION"CT50"
PART_NUMBER"78.22224.2BL"
PACK_TYPE"SMD-BCG6"
CDS_LMAN_SYM_OUTLINE"-50,25,50,-25"
CDS_LIB"w_hdl"
STATUS"NOPOP"
LOCATION"CT50"
VALUE"SC2K2P50V3KX-GP";
"2"
$PN"2"24;
"1"
$PN"1"25;
%"INDUCTOR"
"1","(3175,1950)","0","mstr_discrete","I125";
;
SEC_TYPE"SM"
SEC"1"
ROOM"VDDQ_ABC_PWR_VR"
CDS_LIB"mstr_discrete"
CDS_LOCATION"L7G1"
CDS_SEC"1"
PART_NUMBER"D92183-034"
MATERIAL"IND"
LOCATION"L7G1"
PACK_TYPE"SM"
VALUE"0.12UH";
"INA\NAC"
$PN"1"25;
"INB\NAC"
$PN"2"1;
%"RES"
"1","(-275,2025)","0","mstr_discrete","I126";
;
CDS_SEC"1"
$SEC"1"
CDS_LOCATION"RT33"
ROOM"BMC_DEBUG_HEADER"
BOM_COST"DEBUG"
CDS_LIB"mstr_discrete"
PART_NUMBER"G21497-005"
VALUE"0.0"
TOLERANCE"5%"
MATERIAL"CHIP"
PACK_TYPE"0402"
WATTAGE"1/16W"
LOCATION"RT33";
"B"
$PN"2"34;
"A"
$PN"1"36;
%"RES"
"1","(-225,-325)","0","mstr_discrete","I127";
;
CDS_SEC"1"
$SEC"1"
CDS_LOCATION"RT36"
CDS_LIB"mstr_discrete"
BOM_COST"DEBUG"
ROOM"BMC_DEBUG_HEADER"
LOCATION"RT36"
PACK_TYPE"0402"
MATERIAL"CHIP"
TOLERANCE"5%"
PART_NUMBER"G21497-005"
VALUE"0.0"
WATTAGE"1/16W";
"B"
$PN"2"28;
"A"
$PN"1"29;
%"CAP"
"1","(-1150,-475)","2","mstr_discrete","I128";
;
CDS_SEC"1"
ROOM"VDDQ_ABC_PWR_VR"
CDS_LOCATION"C7G38"
SEC"1"
SPOF"TRUE"
SEC_TYPE"0402"
CDS_LIB"mstr_discrete"
MATERIAL"X7R"
PACK_TYPE"0402"
PART_NUMBER"A36096-104"
LOCATION"C7G38"
VALUE"0.220UF"
VOLTAGE"16V"
TOLERANCE"10%";
"A"
$PN"1"29;
"B"
$PN"2"21;
%"GND"
"1","(2100,1575)","0","mstr_symbols","I19";
;
HDL_POWER"GND"
VOLTAGE"0"
CDS_LIB"mstr_symbols"
SIZE"1B"
BODY_TYPE"PLUMBING"
BOM_COST"PROC_VRD_VCCIN_CPU0"
ROOM"VDDQ_ABC_PWR_VR";
"A\NAC"10;
%"GND"
"1","(-2675,2075)","0","mstr_symbols","I35";
;
CDS_LIB"mstr_symbols"
VOLTAGE"0"
HDL_POWER"GND"
BOM_COST"PROC_VRD_VCCIN_CPU0"
ROOM"VDDQ_ABC_PWR_VR"
SIZE"1B"
BODY_TYPE"PLUMBING";
"A\NAC"11;
%"CAP"
"1","(-1025,1875)","2","mstr_discrete","I44";
;
CDS_SEC"1"
ROOM"VDDQ_ABC_PWR_VR"
CDS_LOCATION"C7G31"
SEC"1"
SPOF"TRUE"
SEC_TYPE"0402"
CDS_LIB"mstr_discrete"
PACK_TYPE"0402"
MATERIAL"X7R"
VOLTAGE"16V"
TOLERANCE"10%"
VALUE"0.220UF"
PART_NUMBER"A36096-104"
LOCATION"C7G31";
"A"
$PN"1"36;
"B"
$PN"2"33;
%"CAP"
"1","(-2675,2525)","0","mstr_discrete","I45";
;
CDS_SEC"1"
SEC_TYPE"0805"
SEC"1"
ROOM"VDDQ_ABC_PWR_VR"
CDS_LOCATION"C3U2"
CDS_LIB"mstr_discrete"
LOCATION"C3U2"
PART_NUMBER"C95333-007"
VALUE"10UF"
TOLERANCE"10%"
PACK_TYPE"0805"
VOLTAGE"16V"
MATERIAL"X6S";
"A"
$PN"1"18;
"B"
$PN"2"11;
%"CAP"
"1","(-2425,2525)","0","mstr_discrete","I46";
;
CDS_SEC"1"
CDS_LOCATION"C3U3"
SEC"1"
SEC_TYPE"0805"
ROOM"VDDQ_ABC_PWR_VR"
CDS_LIB"mstr_discrete"
LOCATION"C3U3"
VALUE"10UF"
MATERIAL"X6S"
PART_NUMBER"C95333-007"
PACK_TYPE"0805"
TOLERANCE"10%"
VOLTAGE"16V";
"A"
$PN"1"18;
"B"
$PN"2"11;
%"CAP"
"1","(-2150,2550)","0","mstr_discrete","I47";
;
CDS_SEC"1"
SEC_TYPE"0805"
ROOM"VDDQ_ABC_PWR_VR"
CDS_LOCATION"C3U4"
SEC"1"
CDS_LIB"mstr_discrete"
LOCATION"C3U4"
PART_NUMBER"C95333-007"
VALUE"10UF"
TOLERANCE"10%"
PACK_TYPE"0805"
VOLTAGE"16V"
MATERIAL"X6S";
"A"
$PN"1"18;
"B"
$PN"2"11;
%"CAP"
"1","(-1900,2475)","0","mstr_discrete","I48";
;
CDS_SEC"1"
ROOM"VDDQ_ABC_PWR_VR"
CDS_LOCATION"C7G37"
SEC"1"
SEC_TYPE"0402"
CDS_LIB"mstr_discrete"
LOCATION"C7G37"
PART_NUMBER"D97712-011"
VALUE"1.0UF"
TOLERANCE"10%"
PACK_TYPE"0402"
VOLTAGE"16V"
MATERIAL"X6S";
"A"
$PN"1"18;
"B"
$PN"2"11;
%"CAP"
"1","(-1400,2475)","0","mstr_discrete","I50";
;
CDS_SEC"1"
ROOM"VDDQ_ABC_PWR_VR"
CDS_LOCATION"C7G33"
SEC"1"
SEC_TYPE"0402"
CDS_LIB"mstr_discrete"
LOCATION"C7G33"
MATERIAL"X6S"
VOLTAGE"16V"
PACK_TYPE"0402"
TOLERANCE"10%"
VALUE"1.0UF"
PART_NUMBER"D97712-011";
"A"
$PN"1"47;
"B"
$PN"2"11;
%"CAP_A"
"1","(-1650,2475)","0","dev_discrete","I51";
;
ROOM"VDDQ_ABC_PWR_VR"
CDS_LOCATION"C7G29"
CDS_SEC"1"
SEC_TYPE"0402V"
SEC"1"
CDS_LIB"dev_discrete"
LOCATION"C7G29"
PART_NUMBER"A36096-030"
VALUE"0.1UF"
TOLERANCE"10%"
PACK_TYPE"0402V"
VOLTAGE"16V"
MATERIAL"X7R";
"B"
$PN"2"11;
"A"
$PN"1"18;
%"RES"
"1","(-1175,3050)","0","mstr_discrete","I52";
;
CDS_SEC"1"
SEC_TYPE"0402"
SEC"1"
CDS_LOCATION"R3U6"
ROOM"VDDQ_ABC_PWR_VR"
CDS_LIB"mstr_discrete"
PACK_TYPE"0402"
MATERIAL"CHIP"
LOCATION"R3U6"
TOLERANCE"1%"
VALUE"1.0"
WATTAGE"1/16W"
PART_NUMBER"G21796-090";
"B"
$PN"2"19;
"A"
$PN"1"47;
%"CAP_A"
"1","(-675,2500)","2","dev_discrete","I53";
;
ROOM"VDDQ_ABC_PWR_VR"
SEC"1"
SEC_TYPE"0402V"
CDS_SEC"1"
CDS_LOCATION"C7G35"
CDS_LIB"dev_discrete"
MATERIAL"X6S"
LOCATION"C7G35"
VALUE"1.0UF"
VOLTAGE"6.3V"
PACK_TYPE"0402V"
PART_NUMBER"D97712-004"
TOLERANCE"10%";
"B"
$PN"2"11;
"A"
$PN"1"19;
%"CAP"
"1","(-500,2525)","0","mstr_discrete","I54";
;
CDS_SEC"1"
ROOM"VDDQ_ABC_PWR_VR"
CDS_LOCATION"C7G34"
SEC"1"
SEC_TYPE"0402"
CDS_LIB"mstr_discrete"
PACK_TYPE"0402"
VALUE"0.22UF"
VOLTAGE"16V"
TOLERANCE"10%"
MATERIAL"X7R"
PART_NUMBER"A36096-155"
LOCATION"C7G34";
"A"
$PN"1"19;
"B"
$PN"2"11;
%"CAP"
"1","(4000,1750)","0","mstr_discrete","I6";
;
CDS_SEC"1"
SEC_TYPE"0805LF"
SEC"1"
BOM_COST"PROC_VRD_VCCIN_CPU0"
ROOM"VDDQ_ABC_PWR_VR"
CDS_LOCATION"C6G3"
VOLTAGE"4V"
CDS_LIB"mstr_discrete"
LOCATION"C6G3"
PART_NUMBER"C95333-002"
VALUE"22UF"
TOLERANCE"20%"
PACK_TYPE"0805LF"
MATERIAL"X6S";
"A"
$PN"1"1;
"B"
$PN"2"14;
%"PVDDQ_ABC"
"1","(4050,-325)","0","mstr_symbols","I64";
;
BOM_COST"PROC_SOCKET "
ROOM"VDDQ_ABC_PWR_VR"
HDL_POWER"PVDDQ_ABC"
VOLTAGE"1.2V"
CDS_LIB"mstr_symbols"
BODY_TYPE"PLUMBING";
"G\NAC"12;
%"INDUCTOR"
"1","(3125,-425)","0","mstr_discrete","I65";
;
CDS_SEC"1"
CDS_LIB"mstr_discrete"
ROOM"VDDQ_ABC_PWR_VR"
CDS_LOCATION"L7G2"
SEC_TYPE"SM"
SEC"1"
LOCATION"L7G2"
PART_NUMBER"D92183-034"
MATERIAL"IND"
PACK_TYPE"SM"
VALUE"0.12UH";
"INA\NAC"
$PN"1"26;
"INB\NAC"
$PN"2"12;
%"CAP"
"1","(4050,-625)","0","mstr_discrete","I68";
;
CDS_SEC"1"
BOM_COST"PROC_VRD_VCCIN_CPU0"
SEC_TYPE"0805LF"
SEC"1"
ROOM"VDDQ_ABC_PWR_VR"
CDS_LOCATION"C7G27"
VOLTAGE"4V"
CDS_LIB"mstr_discrete"
LOCATION"C7G27"
PART_NUMBER"C95333-002"
VALUE"22UF"
TOLERANCE"20%"
PACK_TYPE"0805LF"
MATERIAL"X6S";
"A"
$PN"1"12;
"B"
$PN"2"13;
%"GND"
"1","(4050,-850)","0","mstr_symbols","I69";
;
SIZE"1B"
HDL_POWER"GND"
BODY_TYPE"PLUMBING"
CDS_LIB"mstr_symbols"
VOLTAGE"0"
BOM_COST"PROC_VRD_VCCIN_CPU0"
ROOM"VDDQ_ABC_PWR_VR";
"A\NAC"13;
%"GND"
"1","(4000,1525)","0","mstr_symbols","I7";
;
HDL_POWER"GND"
BOM_COST"PROC_VRD_VCCIN_CPU0"
VOLTAGE"0"
SIZE"1B"
CDS_LIB"mstr_symbols"
BODY_TYPE"PLUMBING"
ROOM"VDDQ_ABC_PWR_VR";
"A\NAC"14;
%"GND"
"1","(2100,-875)","0","mstr_symbols","I70";
;
HDL_POWER"GND"
BODY_TYPE"PLUMBING"
CDS_LIB"mstr_symbols"
SIZE"1B"
VOLTAGE"0"
BOM_COST"PROC_VRD_VCCIN_CPU0"
ROOM":VCCIN_CPU0_PWR_VR";
"A\NAC"15;
%"CAP"
"1","(-450,150)","0","mstr_discrete","I72";
;
CDS_SEC"1"
ROOM"VDDQ_ABC_PWR_VR"
SEC_TYPE"0402"
SEC"1"
CDS_LOCATION"C7G41"
CDS_LIB"mstr_discrete"
PART_NUMBER"A36096-155"
PACK_TYPE"0402"
LOCATION"C7G41"
MATERIAL"X7R"
TOLERANCE"10%"
VALUE"0.22UF"
VOLTAGE"16V";
"A"
$PN"1"20;
"B"
$PN"2"17;
%"CAP_A"
"1","(-575,150)","2","dev_discrete","I73";
;
ROOM"VDDQ_ABC_PWR_VR"
SEC"1"
SEC_TYPE"0402V"
CDS_SEC"1"
CDS_LOCATION"C7G42"
CDS_LIB"dev_discrete"
PACK_TYPE"0402V"
PART_NUMBER"D97712-004"
LOCATION"C7G42"
VOLTAGE"6.3V"
TOLERANCE"10%"
MATERIAL"X6S"
VALUE"1.0UF";
"B"
$PN"2"17;
"A"
$PN"1"20;
%"RES"
"1","(-1200,675)","0","mstr_discrete","I76";
;
CDS_SEC"1"
SEC"1"
SEC_TYPE"0402"
ROOM"VDDQ_ABC_PWR_VR"
CDS_LOCATION"R3U9"
CDS_LIB"mstr_discrete"
PACK_TYPE"0402"
TOLERANCE"1%"
WATTAGE"1/16W"
MATERIAL"CHIP"
LOCATION"R3U9"
PART_NUMBER"G21796-090"
VALUE"1.0";
"B"
$PN"2"20;
"A"
$PN"1"23;
%"CAP"
"1","(-1450,125)","0","mstr_discrete","I77";
;
CDS_SEC"1"
SEC_TYPE"0402"
SEC"1"
ROOM"VDDQ_ABC_PWR_VR"
CDS_LOCATION"C7G40"
CDS_LIB"mstr_discrete"
VALUE"1.0UF"
TOLERANCE"10%"
PART_NUMBER"D97712-011"
MATERIAL"X6S"
VOLTAGE"16V"
LOCATION"C7G40"
PACK_TYPE"0402";
"A"
$PN"1"23;
"B"
$PN"2"17;
%"CAP_A"
"1","(-1675,100)","0","dev_discrete","I78";
;
SEC"1"
SEC_TYPE"0402V"
CDS_SEC"1"
ROOM"VDDQ_ABC_PWR_VR"
CDS_LIB"dev_discrete"
CDS_LOCATION"C7G36"
TOLERANCE"10%"
VALUE"0.1UF"
VOLTAGE"16V"
MATERIAL"X7R"
PACK_TYPE"0402V"
PART_NUMBER"A36096-030"
LOCATION"C7G36";
"B"
$PN"2"17;
"A"
$PN"1"16;
%"CAP"
"1","(-1900,125)","0","mstr_discrete","I79";
;
CDS_SEC"1"
ROOM"VDDQ_ABC_PWR_VR"
SEC"1"
SEC_TYPE"0402"
CDS_LOCATION"C7G30"
CDS_LIB"mstr_discrete"
TOLERANCE"10%"
LOCATION"C7G30"
VALUE"1.0UF"
VOLTAGE"16V"
MATERIAL"X6S"
PART_NUMBER"D97712-011"
PACK_TYPE"0402";
"A"
$PN"1"16;
"B"
$PN"2"17;
%"CAP"
"1","(-2125,100)","0","mstr_discrete","I80";
;
CDS_SEC"1"
SEC_TYPE"0805"
SEC"1"
ROOM"VDDQ_ABC_PWR_VR"
CDS_LIB"mstr_discrete"
CDS_LOCATION"C3U9"
TOLERANCE"10%"
VOLTAGE"16V"
LOCATION"C3U9"
VALUE"10UF"
MATERIAL"X6S"
PART_NUMBER"C95333-007"
PACK_TYPE"0805";
"A"
$PN"1"16;
"B"
$PN"2"17;
%"CAP"
"1","(-2350,125)","0","mstr_discrete","I81";
;
CDS_SEC"1"
ROOM"VDDQ_ABC_PWR_VR"
SEC"1"
SEC_TYPE"0805"
CDS_LOCATION"C3U7"
CDS_LIB"mstr_discrete"
MATERIAL"X6S"
VOLTAGE"16V"
TOLERANCE"10%"
VALUE"10UF"
LOCATION"C3U7"
PART_NUMBER"C95333-007"
PACK_TYPE"0805";
"A"
$PN"1"16;
"B"
$PN"2"17;
%"VCC_CORE"
"1","(-2600,675)","0","mstr_symbols","I83";
;
CDS_LIB"mstr_symbols"
HDL_POWER"VR_FET_SW_P12V_STBY_PVDDQ_ABC";
"A"16;
%"CAP"
"1","(-2600,100)","0","mstr_discrete","I84";
;
CDS_SEC"1"
SEC"1"
SEC_TYPE"0805"
ROOM"VDDQ_ABC_PWR_VR"
CDS_LOCATION"C3U6"
CDS_LIB"mstr_discrete"
LOCATION"C3U6"
VALUE"10UF"
TOLERANCE"10%"
VOLTAGE"16V"
MATERIAL"X6S"
PART_NUMBER"C95333-007"
PACK_TYPE"0805";
"A"
$PN"1"16;
"B"
$PN"2"17;
%"GND"
"1","(-2600,-275)","0","mstr_symbols","I85";
;
SIZE"1B"
HDL_POWER"GND"
CDS_LIB"mstr_symbols"
VOLTAGE"0"
BODY_TYPE"PLUMBING"
BOM_COST"PROC_VRD_VCCIN_CPU0"
ROOM"VDDQ_ABC_PWR_VR";
"A\NAC"17;
%"VCC_CORE"
"1","(-2675,2850)","0","mstr_symbols","I86";
;
CDS_LIB"mstr_symbols"
HDL_POWER"VR_FET_SW_P12V_STBY_PVDDQ_ABC";
"A"18;
%"P5V_STBY"
"1","(0,3200)","0","mstr_symbols","I87";
;
SIZE"1B"
CDS_LIB"mstr_symbols"
VOLTAGE"5.0V"
BODY_TYPE"PLUMBING"
HDL_POWER"P5V_STBY";
"G\NAC"19;
%"P5V_STBY"
"1","(150,850)","0","mstr_symbols","I88";
;
BODY_TYPE"PLUMBING"
CDS_LIB"mstr_symbols"
SIZE"1B"
VOLTAGE"5.0V"
HDL_POWER"P5V_STBY";
"G\NAC"20;
END.
